(kicad_pcb
	(version 20260206)
	(generator "pcbnew")
	(generator_version "10.0")
	(general
		(thickness 1.6)
		(legacy_teardrops no)
	)
	(paper "A4")
	(title_block
		(title "dpb — 14545-sa.0730WZS0815.brd")
		(comment 1 "Honey Badger (Wiwynn) / footprints 123-129 of 1066")
	)
	(layers
		(0 "F.Cu" signal "TOP")
		(4 "In1.Cu" signal "L2GND")
		(6 "In2.Cu" signal "L3")
		(8 "In3.Cu" signal "L4VCC")
		(10 "In4.Cu" signal "L5VCC")
		(12 "In5.Cu" signal "L6")
		(14 "In6.Cu" signal "L7GND")
		(2 "B.Cu" signal "BOTTOM")
		(9 "F.Adhes" user "F.Adhesive")
		(11 "B.Adhes" user "B.Adhesive")
		(13 "F.Paste" user "Package Geometry/Pastemask Top")
		(15 "B.Paste" user "Package Geometry/Pastemask Bottom")
		(5 "F.SilkS" user "Ref Des/Silkscreen Top")
		(7 "B.SilkS" user "Ref Des/Silkscreen Bottom")
		(1 "F.Mask" user "Board Geometry/Soldermask Top")
		(3 "B.Mask" user "Board Geometry/Soldermask Bottom")
		(17 "Dwgs.User" user "User.Drawings")
		(19 "Cmts.User" user "User.Comments")
		(21 "Eco1.User" user "User.Eco1")
		(23 "Eco2.User" user "User.Eco2")
		(25 "Edge.Cuts" user "Board Geometry/Outline")
		(27 "Margin" user)
		(31 "F.CrtYd" user "Package Geometry/Place Bound Top")
		(29 "B.CrtYd" user "Package Geometry/Place Bound Bottom")
		(35 "F.Fab" user "Ref Des/Assembly Top")
		(33 "B.Fab" user "Ref Des/Assembly Bottom")
	)
	(footprint ""
		(layer "F.Cu")
		(at 26.288746 -330.101702 180)
		(property "Reference" "C286"
			(at 0 0 180)
			(layer "F.SilkS")
			(hide yes)
			(effects
				(font
					(size 1.27 1.27)
				)
			)
		)
		(property "Value" "SCD01U50V2KX-1GP"
			(at 1.1811 -2.7051 180)
			(unlocked yes)
			(layer "F.Fab")
			(hide yes)
			(effects
				(font
					(size 1.016 1.016)
					(thickness 0.1524)
				)
			)
		)
		(property "Device Type" "C402H22"
			(at 1.1811 -4.2291 180)
			(unlocked yes)
			(layer "F.Fab")
			(hide yes)
			(effects
				(font
					(size 1.016 1.016)
					(thickness 0.1524)
				)
			)
		)
		(duplicate_pad_numbers_are_jumpers no)
		(fp_rect
			(start -0.4318 0.9525)
			(end 0.4318 -0.9525)
			(stroke
				(width 0)
				(type default)
			)
			(fill no)
			(layer "F.CrtYd")
		)
		(fp_rect
			(start -0.4318 0.9525)
			(end 0.4318 -0.9525)
			(stroke
				(width 0)
				(type default)
			)
			(fill no)
			(layer "F.Fab")
		)
		(pad "1" smd custom
			(at 0 -0.4445 180)
			(size 0.1524 0.1524)
			(layers "F.Cu" "F.Mask" "F.Paste")
			(net "HDD_PRSNT_NET11")
			(options
				(clearance outline)
				(anchor circle)
			)
			(primitives
				(gr_poly
					(pts
						(arc
							(start 0.3048 -0.2032)
							(mid 0.275042 -0.275042)
							(end 0.2032 -0.3048)
						)
						(arc
							(start -0.2032 -0.3048)
							(mid -0.275042 -0.275042)
							(end -0.3048 -0.2032)
						)
						(arc
							(start -0.3048 0.2032)
							(mid -0.275042 0.275042)
							(end -0.2032 0.3048)
						)
						(arc
							(start 0.2032 0.3048)
							(mid 0.275042 0.275042)
							(end 0.3048 0.2032)
						)
					)
					(width 0)
					(fill yes)
				)
			)
		)
		(pad "2" smd custom
			(at 0 0.4445 180)
			(size 0.1524 0.1524)
			(layers "F.Cu" "F.Mask" "F.Paste")
			(net "GND")
			(options
				(clearance outline)
				(anchor circle)
			)
			(primitives
				(gr_poly
					(pts
						(arc
							(start 0.3048 -0.2032)
							(mid 0.275042 -0.275042)
							(end 0.2032 -0.3048)
						)
						(arc
							(start -0.2032 -0.3048)
							(mid -0.275042 -0.275042)
							(end -0.3048 -0.2032)
						)
						(arc
							(start -0.3048 0.2032)
							(mid -0.275042 0.275042)
							(end -0.2032 0.3048)
						)
						(arc
							(start 0.2032 0.3048)
							(mid 0.275042 0.275042)
							(end 0.3048 0.2032)
						)
					)
					(width 0)
					(fill yes)
				)
			)
		)
	)
	(footprint ""
		(layer "F.Cu")
		(at 28.320746 -373.4562 180)
		(property "Reference" "R312"
			(at 0 0 180)
			(layer "F.SilkS")
			(hide yes)
			(effects
				(font
					(size 1.27 1.27)
				)
			)
		)
		(property "Value" "4K7R2J-2-GP"
			(at 0.064008 -3.993896 180)
			(unlocked yes)
			(layer "F.Fab")
			(hide yes)
			(effects
				(font
					(size 1.016 1.016)
					(thickness 0.1524)
				)
			)
		)
		(property "Device Type" "R402H16"
			(at 0.064008 -5.517896 180)
			(unlocked yes)
			(layer "F.Fab")
			(hide yes)
			(effects
				(font
					(size 1.016 1.016)
					(thickness 0.1524)
				)
			)
		)
		(duplicate_pad_numbers_are_jumpers no)
		(fp_line
			(start 0.508 -0.9398)
			(end -0.508 -0.9398)
			(stroke
				(width 0.1524)
				(type default)
			)
			(layer "F.SilkS")
		)
		(fp_line
			(start -0.508 -0.9398)
			(end -0.508 0.9398)
			(stroke
				(width 0.1524)
				(type default)
			)
			(layer "F.SilkS")
		)
		(fp_rect
			(start -0.508 0.9398)
			(end 0.508 -0.9398)
			(stroke
				(width 0)
				(type default)
			)
			(fill no)
			(layer "F.CrtYd")
		)
		(fp_rect
			(start -0.508 0.9398)
			(end 0.508 -0.9398)
			(stroke
				(width 0)
				(type default)
			)
			(fill no)
			(layer "F.Fab")
		)
		(pad "1" smd custom
			(at 0 -0.4445 180)
			(size 0.1397 0.1397)
			(layers "F.Cu" "F.Mask" "F.Paste")
			(net "P3V3")
			(options
				(clearance outline)
				(anchor circle)
			)
			(primitives
				(gr_poly
					(pts
						(arc
							(start -0.1778 -0.2794)
							(mid -0.249642 -0.249642)
							(end -0.2794 -0.1778)
						)
						(arc
							(start -0.2794 0.1778)
							(mid -0.249642 0.249642)
							(end -0.1778 0.2794)
						)
						(arc
							(start 0.1778 0.2794)
							(mid 0.249642 0.249642)
							(end 0.2794 0.1778)
						)
						(arc
							(start 0.2794 -0.1778)
							(mid 0.249642 -0.249642)
							(end 0.1778 -0.2794)
						)
					)
					(width 0)
					(fill yes)
				)
			)
		)
		(pad "2" smd custom
			(at 0 0.4445 180)
			(size 0.1397 0.1397)
			(layers "F.Cu" "F.Mask" "F.Paste")
			(net "I2C_B_TMP1_A1")
			(options
				(clearance outline)
				(anchor circle)
			)
			(primitives
				(gr_poly
					(pts
						(arc
							(start -0.1778 -0.2794)
							(mid -0.249642 -0.249642)
							(end -0.2794 -0.1778)
						)
						(arc
							(start -0.2794 0.1778)
							(mid -0.249642 0.249642)
							(end -0.1778 0.2794)
						)
						(arc
							(start 0.1778 0.2794)
							(mid 0.249642 0.249642)
							(end 0.2794 0.1778)
						)
						(arc
							(start 0.2794 -0.1778)
							(mid 0.249642 -0.249642)
							(end 0.1778 -0.2794)
						)
					)
					(width 0)
					(fill yes)
				)
			)
		)
	)
	(footprint ""
		(layer "F.Cu")
		(at 212.09 -274.193 180)
		(property "Reference" "Q51"
			(at 0 0 180)
			(layer "F.SilkS")
			(hide yes)
			(effects
				(font
					(size 1.27 1.27)
				)
			)
		)
		(property "Value" "2N7002-11-GP"
			(at 0.127 -8.9662 180)
			(unlocked yes)
			(layer "F.Fab")
			(hide yes)
			(effects
				(font
					(size 1.016 1.016)
					(thickness 0.1524)
				)
			)
		)
		(property "Device Type" "SOT23DGS2D4H44"
			(at 0.127 -10.4902 180)
			(unlocked yes)
			(layer "F.Fab")
			(hide yes)
			(effects
				(font
					(size 1.016 1.016)
					(thickness 0.1524)
				)
			)
		)
		(duplicate_pad_numbers_are_jumpers no)
		(fp_line
			(start 1.651 1.778)
			(end 1.651 -1.778)
			(stroke
				(width 0.1524)
				(type default)
			)
			(layer "F.SilkS")
		)
		(fp_line
			(start 1.651 -1.778)
			(end -1.651 -1.778)
			(stroke
				(width 0.1524)
				(type default)
			)
			(layer "F.SilkS")
		)
		(fp_line
			(start -1.651 1.778)
			(end 1.651 1.778)
			(stroke
				(width 0.1524)
				(type default)
			)
			(layer "F.SilkS")
		)
		(fp_line
			(start -1.651 -1.778)
			(end -1.651 1.778)
			(stroke
				(width 0.1524)
				(type default)
			)
			(layer "F.SilkS")
		)
		(fp_poly
			(pts
				(xy -1.778 1.8796) (xy -1.778 -1.8796) (xy 1.778 -1.8796) (xy 1.778 1.8796)
			)
			(stroke
				(width 0)
				(type default)
			)
			(fill no)
			(layer "F.CrtYd")
		)
		(fp_poly
			(pts
				(xy -1.778 1.8796) (xy -1.778 -1.8796) (xy 1.778 -1.8796) (xy 1.778 1.8796)
			)
			(stroke
				(width 0)
				(type default)
			)
			(fill no)
			(layer "F.Fab")
		)
		(pad "D" smd custom
			(at 0 -0.9525 180)
			(size 0.1905 0.1905)
			(layers "F.Cu" "F.Mask" "F.Paste")
			(net "HDD2_LED_G")
			(options
				(clearance outline)
				(anchor circle)
			)
			(primitives
				(gr_poly
					(pts
						(arc
							(start -0.1778 0.5715)
							(mid -0.321484 0.511984)
							(end -0.381 0.3683)
						)
						(arc
							(start -0.381 -0.3683)
							(mid -0.321484 -0.511984)
							(end -0.1778 -0.5715)
						)
						(arc
							(start 0.1778 -0.5715)
							(mid 0.321484 -0.511984)
							(end 0.381 -0.3683)
						)
						(arc
							(start 0.381 0.3683)
							(mid 0.321484 0.511984)
							(end 0.1778 0.5715)
						)
					)
					(width 0)
					(fill yes)
				)
			)
		)
		(pad "G" smd custom
			(at -0.98425 0.9525 180)
			(size 0.1905 0.1905)
			(layers "F.Cu" "F.Mask" "F.Paste")
			(net "HDD2_LED_B")
			(options
				(clearance outline)
				(anchor circle)
			)
			(primitives
				(gr_poly
					(pts
						(arc
							(start -0.1778 0.5715)
							(mid -0.321484 0.511984)
							(end -0.381 0.3683)
						)
						(arc
							(start -0.381 -0.3683)
							(mid -0.321484 -0.511984)
							(end -0.1778 -0.5715)
						)
						(arc
							(start 0.1778 -0.5715)
							(mid 0.321484 -0.511984)
							(end 0.381 -0.3683)
						)
						(arc
							(start 0.381 0.3683)
							(mid 0.321484 0.511984)
							(end 0.1778 0.5715)
						)
					)
					(width 0)
					(fill yes)
				)
			)
		)
		(pad "S" smd custom
			(at 0.98425 0.9525 180)
			(size 0.1905 0.1905)
			(layers "F.Cu" "F.Mask" "F.Paste")
			(net "GND")
			(options
				(clearance outline)
				(anchor circle)
			)
			(primitives
				(gr_poly
					(pts
						(arc
							(start -0.1778 0.5715)
							(mid -0.321484 0.511984)
							(end -0.381 0.3683)
						)
						(arc
							(start -0.381 -0.3683)
							(mid -0.321484 -0.511984)
							(end -0.1778 -0.5715)
						)
						(arc
							(start 0.1778 -0.5715)
							(mid 0.321484 -0.511984)
							(end 0.381 -0.3683)
						)
						(arc
							(start 0.381 0.3683)
							(mid 0.321484 0.511984)
							(end 0.1778 0.5715)
						)
					)
					(width 0)
					(fill yes)
				)
			)
		)
	)
	(footprint ""
		(layer "F.Cu")
		(at 28.320746 -323.116702)
		(property "Reference" "C285"
			(at 0 0 0)
			(layer "F.SilkS")
			(hide yes)
			(effects
				(font
					(size 1.27 1.27)
				)
			)
		)
		(property "Value" "SC10U16V6KX-2GP"
			(at -0.0762 -5.1308 0)
			(unlocked yes)
			(layer "F.Fab")
			(hide yes)
			(effects
				(font
					(size 1.016 1.016)
					(thickness 0.1524)
				)
			)
		)
		(property "Device Type" "C1206H71"
			(at -0.127 -6.6548 0)
			(unlocked yes)
			(layer "F.Fab")
			(hide yes)
			(effects
				(font
					(size 1.016 1.016)
					(thickness 0.1524)
				)
			)
		)
		(duplicate_pad_numbers_are_jumpers no)
		(fp_line
			(start -1.016 -2.2352)
			(end 1.016 -2.2352)
			(stroke
				(width 0.1524)
				(type default)
			)
			(layer "F.SilkS")
		)
		(fp_line
			(start -1.016 -0.8382)
			(end -1.016 -2.2352)
			(stroke
				(width 0.1524)
				(type default)
			)
			(layer "F.SilkS")
		)
		(fp_line
			(start -1.016 2.2352)
			(end -1.016 0.8382)
			(stroke
				(width 0.1524)
				(type default)
			)
			(layer "F.SilkS")
		)
		(fp_line
			(start 1.016 -2.2352)
			(end 1.016 -0.8382)
			(stroke
				(width 0.1524)
				(type default)
			)
			(layer "F.SilkS")
		)
		(fp_line
			(start 1.016 0.8382)
			(end 1.016 2.2352)
			(stroke
				(width 0.1524)
				(type default)
			)
			(layer "F.SilkS")
		)
		(fp_line
			(start 1.016 2.2352)
			(end -1.016 2.2352)
			(stroke
				(width 0.1524)
				(type default)
			)
			(layer "F.SilkS")
		)
		(fp_rect
			(start -1.0922 2.3114)
			(end 1.0922 -2.3114)
			(stroke
				(width 0)
				(type default)
			)
			(fill no)
			(layer "F.CrtYd")
		)
		(fp_poly
			(pts
				(xy 1.0922 -2.3114) (xy 1.0922 2.3114) (xy -1.0922 2.3114) (xy -1.0922 -2.3114)
			)
			(stroke
				(width 0)
				(type default)
			)
			(fill no)
			(layer "F.Fab")
		)
		(pad "1" smd rect
			(at 0 -1.397)
			(size 1.651 1.27)
			(layers "F.Cu" "F.Mask" "F.Paste")
			(net "P5V_HDD11")
		)
		(pad "2" smd rect
			(at 0 1.397)
			(size 1.651 1.27)
			(layers "F.Cu" "F.Mask" "F.Paste")
			(net "GND")
		)
	)
	(footprint ""
		(layer "F.Cu")
		(at 36.4998 -337.0834 90)
		(property "Reference" "Q68"
			(at 0 0 90)
			(layer "F.SilkS")
			(hide yes)
			(effects
				(font
					(size 1.27 1.27)
				)
			)
		)
		(property "Value" "2N7002DW-7F-GP"
			(at -2.3622 -8.2042 90)
			(unlocked yes)
			(layer "F.Fab")
			(hide yes)
			(effects
				(font
					(size 1.016 1.016)
					(thickness 0.1524)
				)
			)
		)
		(property "Device Type" "SOT-363H44"
			(at -2.3622 -10.1092 90)
			(unlocked yes)
			(layer "F.Fab")
			(hide yes)
			(effects
				(font
					(size 1.016 1.016)
					(thickness 0.1524)
				)
			)
		)
		(duplicate_pad_numbers_are_jumpers no)
		(fp_line
			(start 1.4478 -1.7018)
			(end -1.4478 -1.7018)
			(stroke
				(width 0.1524)
				(type default)
			)
			(layer "F.SilkS")
		)
		(fp_line
			(start -1.4478 -1.7018)
			(end -1.4478 1.7018)
			(stroke
				(width 0.1524)
				(type default)
			)
			(layer "F.SilkS")
		)
		(fp_line
			(start -1.27 1.524)
			(end -1.27 0.6604)
			(stroke
				(width 0.4826)
				(type default)
			)
			(layer "F.SilkS")
		)
		(fp_line
			(start 1.4478 1.7018)
			(end 1.4478 -1.7018)
			(stroke
				(width 0.1524)
				(type default)
			)
			(layer "F.SilkS")
		)
		(fp_line
			(start -1.4478 1.7018)
			(end 1.4478 1.7018)
			(stroke
				(width 0.1524)
				(type default)
			)
			(layer "F.SilkS")
		)
		(fp_poly
			(pts
				(xy -1.524 -1.778) (xy 1.524 -1.778) (xy 1.524 1.778) (xy -1.524 1.778)
			)
			(stroke
				(width 0)
				(type default)
			)
			(fill no)
			(layer "F.CrtYd")
		)
		(fp_poly
			(pts
				(xy -1.524 -1.778) (xy 1.524 -1.778) (xy 1.524 1.778) (xy -1.524 1.778)
			)
			(stroke
				(width 0)
				(type default)
			)
			(fill no)
			(layer "F.Fab")
		)
		(pad "1" smd rect
			(at -0.65024 0.9398 90)
			(size 0.4064 1.016)
			(layers "F.Cu" "F.Mask" "F.Paste")
			(net "P3V3_HDD11_LED")
		)
		(pad "2" smd rect
			(at 0 0.9398 90)
			(size 0.4064 1.016)
			(layers "F.Cu" "F.Mask" "F.Paste")
			(net "HDD11_LED_G")
		)
		(pad "3" smd rect
			(at 0.65024 0.9398 90)
			(size 0.4064 1.016)
			(layers "F.Cu" "F.Mask" "F.Paste")
			(net "P5VC")
		)
		(pad "4" smd rect
			(at 0.65024 -0.9398 90)
			(size 0.4064 1.016)
			(layers "F.Cu" "F.Mask" "F.Paste")
			(net "P5VC_HDD11_LED")
		)
		(pad "5" smd rect
			(at 0 -0.9398 90)
			(size 0.4064 1.016)
			(layers "F.Cu" "F.Mask" "F.Paste")
			(net "HDD11_LED_G")
		)
		(pad "6" smd rect
			(at -0.65024 -0.9398 90)
			(size 0.4064 1.016)
			(layers "F.Cu" "F.Mask" "F.Paste")
			(net "P3V3")
		)
	)
	(footprint ""
		(layer "F.Cu")
		(at 80.7466 -26.7208 -90)
		(property "Reference" "R405"
			(at 0 0 270)
			(layer "F.SilkS")
			(hide yes)
			(effects
				(font
					(size 1.27 1.27)
				)
			)
		)
		(property "Value" "10KR2F-2-GP"
			(at 0.064008 -3.993896 270)
			(unlocked yes)
			(layer "F.Fab")
			(hide yes)
			(effects
				(font
					(size 1.016 1.016)
					(thickness 0.1524)
				)
			)
		)
		(property "Device Type" "R402H16"
			(at 0.064008 -5.517896 270)
			(unlocked yes)
			(layer "F.Fab")
			(hide yes)
			(effects
				(font
					(size 1.016 1.016)
					(thickness 0.1524)
				)
			)
		)
		(duplicate_pad_numbers_are_jumpers no)
		(fp_line
			(start -0.508 -0.9398)
			(end -0.508 0.9398)
			(stroke
				(width 0.1524)
				(type default)
			)
			(layer "F.SilkS")
		)
		(fp_line
			(start 0.508 -0.9398)
			(end -0.508 -0.9398)
			(stroke
				(width 0.1524)
				(type default)
			)
			(layer "F.SilkS")
		)
		(fp_rect
			(start -0.508 0.9398)
			(end 0.508 -0.9398)
			(stroke
				(width 0)
				(type default)
			)
			(fill no)
			(layer "F.CrtYd")
		)
		(fp_rect
			(start -0.508 0.9398)
			(end 0.508 -0.9398)
			(stroke
				(width 0)
				(type default)
			)
			(fill no)
			(layer "F.Fab")
		)
		(pad "1" smd custom
			(at 0 -0.4445 270)
			(size 0.1397 0.1397)
			(layers "F.Cu" "F.Mask" "F.Paste")
			(net "P12V")
			(options
				(clearance outline)
				(anchor circle)
			)
			(primitives
				(gr_poly
					(pts
						(arc
							(start -0.1778 -0.2794)
							(mid -0.249642 -0.249642)
							(end -0.2794 -0.1778)
						)
						(arc
							(start -0.2794 0.1778)
							(mid -0.249642 0.249642)
							(end -0.1778 0.2794)
						)
						(arc
							(start 0.1778 0.2794)
							(mid 0.249642 0.249642)
							(end 0.2794 0.1778)
						)
						(arc
							(start 0.2794 -0.1778)
							(mid 0.249642 -0.249642)
							(end 0.1778 -0.2794)
						)
					)
					(width 0)
					(fill yes)
				)
			)
		)
		(pad "2" smd custom
			(at 0 0.4445 270)
			(size 0.1397 0.1397)
			(layers "F.Cu" "F.Mask" "F.Paste")
			(net "HDD14_LED_G")
			(options
				(clearance outline)
				(anchor circle)
			)
			(primitives
				(gr_poly
					(pts
						(arc
							(start -0.1778 -0.2794)
							(mid -0.249642 -0.249642)
							(end -0.2794 -0.1778)
						)
						(arc
							(start -0.2794 0.1778)
							(mid -0.249642 0.249642)
							(end -0.1778 0.2794)
						)
						(arc
							(start 0.1778 0.2794)
							(mid 0.249642 0.249642)
							(end 0.2794 0.1778)
						)
						(arc
							(start 0.2794 -0.1778)
							(mid 0.249642 -0.249642)
							(end 0.1778 -0.2794)
						)
					)
					(width 0)
					(fill yes)
				)
			)
		)
	)
	(footprint ""
		(layer "F.Cu")
		(at 240.284 -375.285 -90)
		(property "Reference" "C349"
			(at 0 0 270)
			(layer "F.SilkS")
			(hide yes)
			(effects
				(font
					(size 1.27 1.27)
				)
			)
		)
		(property "Value" "SC10U25V6KX-1GP"
			(at -0.0762 -5.1308 270)
			(unlocked yes)
			(layer "F.Fab")
			(hide yes)
			(effects
				(font
					(size 1.016 1.016)
					(thickness 0.1524)
				)
			)
		)
		(property "Device Type" "C1206H71"
			(at -0.127 -6.6548 270)
			(unlocked yes)
			(layer "F.Fab")
			(hide yes)
			(effects
				(font
					(size 1.016 1.016)
					(thickness 0.1524)
				)
			)
		)
		(duplicate_pad_numbers_are_jumpers no)
		(fp_line
			(start -1.016 2.2352)
			(end -1.016 0.8382)
			(stroke
				(width 0.1524)
				(type default)
			)
			(layer "F.SilkS")
		)
		(fp_line
			(start 1.016 2.2352)
			(end -1.016 2.2352)
			(stroke
				(width 0.1524)
				(type default)
			)
			(layer "F.SilkS")
		)
		(fp_line
			(start 1.016 0.8382)
			(end 1.016 2.2352)
			(stroke
				(width 0.1524)
				(type default)
			)
			(layer "F.SilkS")
		)
		(fp_line
			(start -1.016 -0.8382)
			(end -1.016 -2.2352)
			(stroke
				(width 0.1524)
				(type default)
			)
			(layer "F.SilkS")
		)
		(fp_line
			(start -1.016 -2.2352)
			(end 1.016 -2.2352)
			(stroke
				(width 0.1524)
				(type default)
			)
			(layer "F.SilkS")
		)
		(fp_line
			(start 1.016 -2.2352)
			(end 1.016 -0.8382)
			(stroke
				(width 0.1524)
				(type default)
			)
			(layer "F.SilkS")
		)
		(fp_rect
			(start -1.0922 2.3114)
			(end 1.0922 -2.3114)
			(stroke
				(width 0)
				(type default)
			)
			(fill no)
			(layer "F.CrtYd")
		)
		(fp_poly
			(pts
				(xy 1.0922 -2.3114) (xy 1.0922 2.3114) (xy -1.0922 2.3114) (xy -1.0922 -2.3114)
			)
			(stroke
				(width 0)
				(type default)
			)
			(fill no)
			(layer "F.Fab")
		)
		(pad "1" smd rect
			(at 0 -1.397 270)
			(size 1.651 1.27)
			(layers "F.Cu" "F.Mask" "F.Paste")
			(net "P12V")
		)
		(pad "2" smd rect
			(at 0 1.397 270)
			(size 1.651 1.27)
			(layers "F.Cu" "F.Mask" "F.Paste")
			(net "GND")
		)
	)
)
